(kicad_pcb
	(version 20260206)
	(generator "pcbnew")
	(generator_version "10.0")
	(general
		(thickness 1.6)
		(legacy_teardrops no)
	)
	(paper "A4")
	(title_block
		(title "04192023_DAF0TMB3IC0_F0TG_MB_C_brd_V02_OCP.brd")
		(comment 1 "Grand Teton / footprints 1264-1267 of 8354")
	)
	(layers
		(0 "F.Cu" signal "TOP")
		(4 "In1.Cu" signal "GND")
		(6 "In2.Cu" signal "IN1")
		(8 "In3.Cu" signal "GND1")
		(10 "In4.Cu" signal "IN2")
		(12 "In5.Cu" signal "GND2")
		(14 "In6.Cu" signal "IN3")
		(16 "In7.Cu" signal "GND3")
		(18 "In8.Cu" signal "VCC")
		(20 "In9.Cu" signal "VCC1")
		(22 "In10.Cu" signal "GND4")
		(24 "In11.Cu" signal "IN4")
		(26 "In12.Cu" signal "GND5")
		(28 "In13.Cu" signal "IN5")
		(30 "In14.Cu" signal "GND6")
		(32 "In15.Cu" signal "IN6")
		(34 "In16.Cu" signal "GND7")
		(2 "B.Cu" signal "BOTTOM")
		(9 "F.Adhes" user "F.Adhesive")
		(11 "B.Adhes" user "B.Adhesive")
		(13 "F.Paste" user "Package Geometry/Pastemask Top")
		(15 "B.Paste" user "Package Geometry/Pastemask Bottom")
		(5 "F.SilkS" user "Ref Des/Silkscreen Top")
		(7 "B.SilkS" user "Ref Des/Silkscreen Bottom")
		(1 "F.Mask" user "Board Geometry/Soldermask Top")
		(3 "B.Mask" user "Board Geometry/Soldermask Bottom")
		(17 "Dwgs.User" user "User.Drawings")
		(19 "Cmts.User" user "User.Comments")
		(21 "Eco1.User" user "User.Eco1")
		(23 "Eco2.User" user "User.Eco2")
		(25 "Edge.Cuts" user "Board Geometry/Outline")
		(27 "Margin" user)
		(31 "F.CrtYd" user "Package Geometry/Place Bound Top")
		(29 "B.CrtYd" user "Package Geometry/Place Bound Bottom")
		(35 "F.Fab" user "Ref Des/Assembly Top")
		(33 "B.Fab" user "Ref Des/Assembly Bottom")
	)
	(footprint ""
		(layer "F.Cu")
		(at 140.765784 -47.309024 90)
		(property "Reference" "R4450"
			(at 0 0 90)
			(layer "F.SilkS")
			(hide yes)
			(effects
				(font
					(size 1.27 1.27)
				)
			)
		)
		(property "Value" ""
			(at 0 0 90)
			(layer "F.Fab")
			(effects
				(font
					(size 1.27 1.27)
				)
			)
		)
		(duplicate_pad_numbers_are_jumpers no)
		(fp_line
			(start 0.7874 -0.4064)
			(end 0.7874 0.4064)
			(stroke
				(width 0.1524)
				(type default)
			)
			(layer "F.SilkS")
		)
		(fp_line
			(start -0.7874 -0.4064)
			(end 0.7874 -0.4064)
			(stroke
				(width 0.1524)
				(type default)
			)
			(layer "F.SilkS")
		)
		(fp_line
			(start 0.7874 0.4064)
			(end -0.7874 0.4064)
			(stroke
				(width 0.1524)
				(type default)
			)
			(layer "F.SilkS")
		)
		(fp_line
			(start -0.7874 0.4064)
			(end -0.7874 -0.4064)
			(stroke
				(width 0.1524)
				(type default)
			)
			(layer "F.SilkS")
		)
		(fp_line
			(start -0.12065 -0.305054)
			(end -0.12065 -0.2794)
			(stroke
				(width 0.1)
				(type default)
			)
			(layer "F.Fab")
		)
		(fp_line
			(start -0.67945 -0.305054)
			(end -0.12065 -0.305054)
			(stroke
				(width 0.1)
				(type default)
			)
			(layer "F.Fab")
		)
		(fp_line
			(start 0.67945 -0.3048)
			(end 0.67945 0.3048)
			(stroke
				(width 0.1)
				(type default)
			)
			(layer "F.Fab")
		)
		(fp_line
			(start 0.12065 -0.3048)
			(end 0.67945 -0.3048)
			(stroke
				(width 0.1)
				(type default)
			)
			(layer "F.Fab")
		)
		(fp_line
			(start 0.12065 -0.2794)
			(end 0.12065 -0.3048)
			(stroke
				(width 0.1)
				(type default)
			)
			(layer "F.Fab")
		)
		(fp_line
			(start -0.12065 -0.2794)
			(end 0.12065 -0.2794)
			(stroke
				(width 0.1)
				(type default)
			)
			(layer "F.Fab")
		)
		(fp_line
			(start 0.120396 0.2794)
			(end -0.12065 0.2794)
			(stroke
				(width 0.1)
				(type default)
			)
			(layer "F.Fab")
		)
		(fp_line
			(start -0.12065 0.2794)
			(end -0.12065 0.3048)
			(stroke
				(width 0.1)
				(type default)
			)
			(layer "F.Fab")
		)
		(fp_line
			(start 0.67945 0.3048)
			(end 0.120396 0.3048)
			(stroke
				(width 0.1)
				(type default)
			)
			(layer "F.Fab")
		)
		(fp_line
			(start 0.120396 0.3048)
			(end 0.120396 0.2794)
			(stroke
				(width 0.1)
				(type default)
			)
			(layer "F.Fab")
		)
		(fp_line
			(start -0.12065 0.3048)
			(end -0.67945 0.3048)
			(stroke
				(width 0.1)
				(type default)
			)
			(layer "F.Fab")
		)
		(fp_line
			(start -0.67945 0.3048)
			(end -0.67945 -0.305054)
			(stroke
				(width 0.1)
				(type default)
			)
			(layer "F.Fab")
		)
		(pad "1" smd circle
			(at -0.40005 0 90)
			(size 0 0)
			(layers "F.Cu" "F.Mask" "F.Paste")
			(net "USB_CPU0_HUB1_VBUS_DS")
		)
		(pad "2" smd circle
			(at 0.40005 0 90)
			(size 0 0)
			(layers "F.Cu" "F.Mask" "F.Paste")
			(net "P5V_AUX")
		)
	)
	(footprint ""
		(layer "F.Cu")
		(at 283.702506 -346.71635)
		(property "Reference" "PU19"
			(at -2.524506 -7.84098 0)
			(unlocked yes)
			(layer "F.SilkS")
			(effects
				(font
					(size 0.7874 0.5842)
					(thickness 0.1524)
				)
				(justify left)
			)
		)
		(property "Value" ""
			(at 0 0 0)
			(layer "F.Fab")
			(effects
				(font
					(size 1.27 1.27)
				)
			)
		)
		(duplicate_pad_numbers_are_jumpers no)
		(fp_line
			(start -2.500122 -2.999994)
			(end -2.24409 -2.999994)
			(stroke
				(width 0.1524)
				(type default)
			)
			(layer "F.SilkS")
		)
		(fp_line
			(start -2.500122 -2.529078)
			(end -2.500122 -2.999994)
			(stroke
				(width 0.1524)
				(type default)
			)
			(layer "F.SilkS")
		)
		(fp_line
			(start -2.500122 0.6604)
			(end -2.500122 0.229108)
			(stroke
				(width 0.1524)
				(type default)
			)
			(layer "F.SilkS")
		)
		(fp_line
			(start -2.500122 2.999994)
			(end -2.500122 2.339594)
			(stroke
				(width 0.1524)
				(type default)
			)
			(layer "F.SilkS")
		)
		(fp_line
			(start -2.2987 2.999994)
			(end -2.500122 2.999994)
			(stroke
				(width 0.1524)
				(type default)
			)
			(layer "F.SilkS")
		)
		(fp_line
			(start 2.31394 -2.999994)
			(end 2.500122 -2.999994)
			(stroke
				(width 0.1524)
				(type default)
			)
			(layer "F.SilkS")
		)
		(fp_line
			(start 2.500122 -2.999994)
			(end 2.500122 -2.44348)
			(stroke
				(width 0.1524)
				(type default)
			)
			(layer "F.SilkS")
		)
		(fp_line
			(start 2.500122 2.339594)
			(end 2.500122 2.999994)
			(stroke
				(width 0.1524)
				(type default)
			)
			(layer "F.SilkS")
		)
		(fp_line
			(start 2.500122 2.999994)
			(end 2.2987 2.999994)
			(stroke
				(width 0.1524)
				(type default)
			)
			(layer "F.SilkS")
		)
		(fp_poly
			(pts
				(xy -3.467354 -2.685288) (xy -2.981706 -3.170936) (xy -2.738882 -2.442464)
			)
			(stroke
				(width 0)
				(type default)
			)
			(fill yes)
			(layer "F.SilkS")
		)
		(fp_line
			(start -2.500122 -2.999994)
			(end 2.500122 -2.999994)
			(stroke
				(width 0.1)
				(type default)
			)
			(layer "F.Fab")
		)
		(fp_line
			(start -2.500122 2.999994)
			(end -2.500122 -2.999994)
			(stroke
				(width 0.1)
				(type default)
			)
			(layer "F.Fab")
		)
		(fp_line
			(start 2.500122 -2.999994)
			(end 2.500122 2.999994)
			(stroke
				(width 0.1)
				(type default)
			)
			(layer "F.Fab")
		)
		(fp_line
			(start 2.500122 2.999994)
			(end -2.500122 2.999994)
			(stroke
				(width 0.1)
				(type default)
			)
			(layer "F.Fab")
		)
		(fp_poly
			(pts
				(xy -4.218432 -2.783078) (xy -4.218432 -1.767078) (xy -3.202432 -2.275078)
			)
			(stroke
				(width 0)
				(type default)
			)
			(fill yes)
			(layer "F.Fab")
		)
		(pad "1" smd rect
			(at -2.400046 -2.275078 90)
			(size 0.2286 0.6096)
			(layers "F.Cu" "F.Mask" "F.Paste")
			(net "PVDDIO_P0_VOS3")
		)
		(pad "2" smd rect
			(at -2.400046 -1.82499 90)
			(size 0.2286 0.6096)
			(layers "F.Cu" "F.Mask" "F.Paste")
			(net "GND")
		)
		(pad "3" smd rect
			(at -2.400046 -1.374902 90)
			(size 0.2286 0.6096)
			(layers "F.Cu" "F.Mask" "F.Paste")
			(net "PVDDIO_P0_VCC3")
		)
		(pad "4" smd rect
			(at -2.400046 -0.925068 90)
			(size 0.2286 0.6096)
			(layers "F.Cu" "F.Mask" "F.Paste")
			(net "PVDDCR_CPU1_P0_PVCC")
		)
		(pad "5" smd rect
			(at -2.400046 -0.47498 90)
			(size 0.2286 0.6096)
			(layers "F.Cu" "F.Mask" "F.Paste")
			(net "GND")
		)
		(pad "6" smd rect
			(at -2.400046 -0.024892 90)
			(size 0.2286 0.6096)
			(layers "F.Cu" "F.Mask" "F.Paste")
			(net "NC_PVDDIO_P0_GL1_3")
		)
		(pad "7_9-20_24" smd circle
			(at 0 1.150112 90)
			(size 0 0)
			(layers "F.Cu" "F.Mask" "F.Paste")
			(net "GND")
		)
		(pad "10_19" smd rect
			(at 0 2.899918 90)
			(size 0.6096 4.318)
			(layers "F.Cu" "F.Mask" "F.Paste")
			(net "SW_PVDDIO_P0_SW3")
		)
		(pad "25_29" smd rect
			(at 1.549908 -1.279906 270)
			(size 2.0574 2.3114)
			(layers "F.Cu" "F.Mask" "F.Paste")
			(net "SW_P12V_AUX_PVDDIO_P0_FLT")
		)
		(pad "30" smd rect
			(at 2.05994 -2.899918)
			(size 0.2286 0.6096)
			(layers "F.Cu" "F.Mask" "F.Paste")
			(net "SW_P12V_AUX_PVDDIO_P0_FLT")
		)
		(pad "31" smd rect
			(at 1.610106 -2.899918)
			(size 0.2286 0.6096)
			(layers "F.Cu" "F.Mask" "F.Paste")
			(net "NC_PVDDIO_P0_DNC3")
		)
		(pad "32" smd rect
			(at 1.160018 -2.899918)
			(size 0.2286 0.6096)
			(layers "F.Cu" "F.Mask" "F.Paste")
			(net "SW_PVDDIO_P0_BOOTR3")
		)
		(pad "33" smd rect
			(at 0.70993 -2.899918)
			(size 0.2286 0.6096)
			(layers "F.Cu" "F.Mask" "F.Paste")
			(net "SW_PVDDIO_P0_BOOT3")
		)
		(pad "34" smd rect
			(at 0.260096 -2.899918)
			(size 0.2286 0.6096)
			(layers "F.Cu" "F.Mask" "F.Paste")
			(net "PVDDIO_P0_PWM3")
		)
		(pad "35" smd rect
			(at -0.189992 -2.899918)
			(size 0.2286 0.6096)
			(layers "F.Cu" "F.Mask" "F.Paste")
			(net "PVDDIO_P0_VCC3")
		)
		(pad "36" smd rect
			(at -0.64008 -2.899918)
			(size 0.2286 0.6096)
			(layers "F.Cu" "F.Mask" "F.Paste")
			(net "PVDDIO_P0_TEMP1")
		)
		(pad "37" smd rect
			(at -1.089914 -2.899918)
			(size 0.2286 0.6096)
			(layers "F.Cu" "F.Mask" "F.Paste")
			(net "PVDDIO_P0_LSET3")
		)
		(pad "38" smd rect
			(at -1.540002 -2.899918)
			(size 0.2286 0.6096)
			(layers "F.Cu" "F.Mask" "F.Paste")
			(net "PVDDIO_P0_IMON3")
		)
		(pad "39" smd rect
			(at -1.99009 -2.899918)
			(size 0.2286 0.6096)
			(layers "F.Cu" "F.Mask" "F.Paste")
			(net "PVDDCR_CPU1_P0_VCCS")
		)
		(pad "40" smd rect
			(at -0.87503 -1.27508)
			(size 1.7526 1.9558)
			(layers "F.Cu" "F.Mask" "F.Paste")
			(net "GND")
		)
		(pad "41" smd rect
			(at -1.525016 0.249936 270)
			(size 0.3048 0.4572)
			(layers "F.Cu" "F.Mask" "F.Paste")
			(net "NC_PVDDIO_P0_GL2_3")
		)
		(zone
			(layer "F.Cu")
			(hatch none 0.5)
			(connect_pads
				(clearance 0)
			)
			(min_thickness 0.25)
			(keepout
				(tracks not_allowed)
				(vias allowed)
				(pads allowed)
				(copperpour not_allowed)
				(footprints allowed)
			)
			(placement
				(enabled no)
				(sheetname "")
			)
			(fill
				(thermal_gap 0.5)
				(thermal_bridge_width 0.5)
				(island_removal_mode 0)
			)
			(polygon
				(pts
					(xy 281.202384 -344.124788) (xy 281.202384 -344.465656) (xy 286.202628 -344.465656) (xy 286.202628 -344.13063)
					(xy 285.912306 -344.13063) (xy 285.912306 -344.172032) (xy 281.492706 -344.172032) (xy 281.492706 -344.124788)
				)
			)
		)
		(zone
			(layer "F.Cu")
			(hatch none 0.5)
			(connect_pads
				(clearance 0)
			)
			(min_thickness 0.25)
			(keepout
				(tracks not_allowed)
				(vias allowed)
				(pads allowed)
				(copperpour not_allowed)
				(footprints allowed)
			)
			(placement
				(enabled no)
				(sheetname "")
			)
			(fill
				(thermal_gap 0.5)
				(thermal_bridge_width 0.5)
				(island_removal_mode 0)
			)
			(polygon
				(pts
					(xy 283.754576 -346.96273) (xy 283.754576 -349.02013) (xy 281.900376 -349.02013) (xy 281.900376 -348.779084)
					(xy 281.65806 -348.779084) (xy 281.65806 -349.260668) (xy 285.474918 -349.260668) (xy 285.474918 -349.075756)
					(xy 284.045914 -349.075756) (xy 284.045914 -346.916756) (xy 286.202628 -346.916756) (xy 286.202628 -346.667074)
					(xy 284.050232 -346.667074)
				)
			)
		)
	)
	(footprint ""
		(layer "F.Cu")
		(at 285.980886 -101.09708)
		(property "Reference" "C1515"
			(at 0 0 0)
			(layer "F.SilkS")
			(hide yes)
			(effects
				(font
					(size 1.27 1.27)
				)
			)
		)
		(property "Value" ""
			(at 0 0 0)
			(layer "F.Fab")
			(effects
				(font
					(size 1.27 1.27)
				)
			)
		)
		(duplicate_pad_numbers_are_jumpers no)
		(fp_line
			(start -0.7874 -0.4064)
			(end 0.7874 -0.4064)
			(stroke
				(width 0.1524)
				(type default)
			)
			(layer "F.SilkS")
		)
		(fp_line
			(start -0.7874 0.4064)
			(end -0.7874 -0.4064)
			(stroke
				(width 0.1524)
				(type default)
			)
			(layer "F.SilkS")
		)
		(fp_line
			(start 0.7874 -0.4064)
			(end 0.7874 0.4064)
			(stroke
				(width 0.1524)
				(type default)
			)
			(layer "F.SilkS")
		)
		(fp_line
			(start 0.7874 0.4064)
			(end -0.7874 0.4064)
			(stroke
				(width 0.1524)
				(type default)
			)
			(layer "F.SilkS")
		)
		(fp_line
			(start -0.67945 -0.305054)
			(end -0.12065 -0.305054)
			(stroke
				(width 0.1)
				(type default)
			)
			(layer "F.Fab")
		)
		(fp_line
			(start -0.67945 0.3048)
			(end -0.67945 -0.305054)
			(stroke
				(width 0.1)
				(type default)
			)
			(layer "F.Fab")
		)
		(fp_line
			(start -0.12065 -0.305054)
			(end -0.12065 -0.2794)
			(stroke
				(width 0.1)
				(type default)
			)
			(layer "F.Fab")
		)
		(fp_line
			(start -0.12065 -0.2794)
			(end 0.12065 -0.2794)
			(stroke
				(width 0.1)
				(type default)
			)
			(layer "F.Fab")
		)
		(fp_line
			(start -0.12065 0.2794)
			(end -0.12065 0.3048)
			(stroke
				(width 0.1)
				(type default)
			)
			(layer "F.Fab")
		)
		(fp_line
			(start -0.12065 0.3048)
			(end -0.67945 0.3048)
			(stroke
				(width 0.1)
				(type default)
			)
			(layer "F.Fab")
		)
		(fp_line
			(start 0.120396 0.2794)
			(end -0.12065 0.2794)
			(stroke
				(width 0.1)
				(type default)
			)
			(layer "F.Fab")
		)
		(fp_line
			(start 0.120396 0.3048)
			(end 0.120396 0.2794)
			(stroke
				(width 0.1)
				(type default)
			)
			(layer "F.Fab")
		)
		(fp_line
			(start 0.12065 -0.3048)
			(end 0.67945 -0.3048)
			(stroke
				(width 0.1)
				(type default)
			)
			(layer "F.Fab")
		)
		(fp_line
			(start 0.12065 -0.2794)
			(end 0.12065 -0.3048)
			(stroke
				(width 0.1)
				(type default)
			)
			(layer "F.Fab")
		)
		(fp_line
			(start 0.67945 -0.3048)
			(end 0.67945 0.3048)
			(stroke
				(width 0.1)
				(type default)
			)
			(layer "F.Fab")
		)
		(fp_line
			(start 0.67945 0.3048)
			(end 0.120396 0.3048)
			(stroke
				(width 0.1)
				(type default)
			)
			(layer "F.Fab")
		)
		(pad "1" smd circle
			(at -0.40005 0)
			(size 0 0)
			(layers "F.Cu" "F.Mask" "F.Paste")
			(net "PVDD18_S5_P0")
		)
		(pad "2" smd circle
			(at 0.40005 0)
			(size 0 0)
			(layers "F.Cu" "F.Mask" "F.Paste")
			(net "GND")
		)
	)
	(footprint ""
		(layer "F.Cu")
		(at 356.567232 -261.747762 -90)
		(property "Reference" "C2642"
			(at 0 0 270)
			(layer "F.SilkS")
			(hide yes)
			(effects
				(font
					(size 1.27 1.27)
				)
			)
		)
		(property "Value" ""
			(at 0 0 270)
			(layer "F.Fab")
			(effects
				(font
					(size 1.27 1.27)
				)
			)
		)
		(duplicate_pad_numbers_are_jumpers no)
		(fp_line
			(start -0.7874 0.4064)
			(end -0.7874 -0.4064)
			(stroke
				(width 0.1524)
				(type default)
			)
			(layer "F.SilkS")
		)
		(fp_line
			(start 0.7874 0.4064)
			(end -0.7874 0.4064)
			(stroke
				(width 0.1524)
				(type default)
			)
			(layer "F.SilkS")
		)
		(fp_line
			(start -0.7874 -0.4064)
			(end 0.7874 -0.4064)
			(stroke
				(width 0.1524)
				(type default)
			)
			(layer "F.SilkS")
		)
		(fp_line
			(start 0.7874 -0.4064)
			(end 0.7874 0.4064)
			(stroke
				(width 0.1524)
				(type default)
			)
			(layer "F.SilkS")
		)
		(fp_line
			(start -0.67945 0.3048)
			(end -0.67945 -0.305054)
			(stroke
				(width 0.1)
				(type default)
			)
			(layer "F.Fab")
		)
		(fp_line
			(start -0.12065 0.3048)
			(end -0.67945 0.3048)
			(stroke
				(width 0.1)
				(type default)
			)
			(layer "F.Fab")
		)
		(fp_line
			(start 0.120396 0.3048)
			(end 0.120396 0.2794)
			(stroke
				(width 0.1)
				(type default)
			)
			(layer "F.Fab")
		)
		(fp_line
			(start 0.67945 0.3048)
			(end 0.120396 0.3048)
			(stroke
				(width 0.1)
				(type default)
			)
			(layer "F.Fab")
		)
		(fp_line
			(start -0.12065 0.2794)
			(end -0.12065 0.3048)
			(stroke
				(width 0.1)
				(type default)
			)
			(layer "F.Fab")
		)
		(fp_line
			(start 0.120396 0.2794)
			(end -0.12065 0.2794)
			(stroke
				(width 0.1)
				(type default)
			)
			(layer "F.Fab")
		)
		(fp_line
			(start -0.12065 -0.2794)
			(end 0.12065 -0.2794)
			(stroke
				(width 0.1)
				(type default)
			)
			(layer "F.Fab")
		)
		(fp_line
			(start 0.12065 -0.2794)
			(end 0.12065 -0.3048)
			(stroke
				(width 0.1)
				(type default)
			)
			(layer "F.Fab")
		)
		(fp_line
			(start 0.12065 -0.3048)
			(end 0.67945 -0.3048)
			(stroke
				(width 0.1)
				(type default)
			)
			(layer "F.Fab")
		)
		(fp_line
			(start 0.67945 -0.3048)
			(end 0.67945 0.3048)
			(stroke
				(width 0.1)
				(type default)
			)
			(layer "F.Fab")
		)
		(fp_line
			(start -0.67945 -0.305054)
			(end -0.12065 -0.305054)
			(stroke
				(width 0.1)
				(type default)
			)
			(layer "F.Fab")
		)
		(fp_line
			(start -0.12065 -0.305054)
			(end -0.12065 -0.2794)
			(stroke
				(width 0.1)
				(type default)
			)
			(layer "F.Fab")
		)
		(pad "1" smd circle
			(at -0.40005 0 270)
			(size 0 0)
			(layers "F.Cu" "F.Mask" "F.Paste")
			(net "PVDD11_S3_P0")
		)
		(pad "2" smd circle
			(at 0.40005 0 270)
			(size 0 0)
			(layers "F.Cu" "F.Mask" "F.Paste")
			(net "GND")
		)
	)
)
